# S9S_MB_2U (Grand Teton) — schematic netlist excerpt (pin names and nets, part order shuffled) for the footprints in the layout excerpt that follows; sources: Cadence DE-HDL packaged netlist, KiCad conversion of 03242023_DA0F0TMBIJ0_F0T_Motherboard_J_brd_V01_OCP.brd

PR3821  Q_RES  30.1K 1% EMPTY  pkg 0402LF  page 162 : A = P12V_OCP_CB_2 ; B = GND

U253  74LVC2G17GW  IC  pkg SOT363  page 149
  A0  = GPU_FPGA_BOOT_EN
  GND  = GND
  A1  = GPU_BASE_STBY_EN
  B1  = GPU_BASE_STBY_EN_BUF_R
  VCC  = P3V3_AUX
  B0  = GPU_FPGA_BOOT_EN_BUF_R

(kicad_pcb
	(version 20260206)
	(generator "pcbnew")
	(generator_version "10.0")
	(general
		(thickness 1.6)
		(legacy_teardrops no)
	)
	(paper "A4")
	(title_block
		(title "03242023_DA0F0TMBIJ0_F0T_Motherboard_J_brd_V01_OCP.brd")
		(comment 1 "Grand Teton / footprints 3196-3197 of 6105")
	)
	(layers
		(0 "F.Cu" signal "TOP")
		(4 "In1.Cu" signal "GND")
		(6 "In2.Cu" signal "IN1")
		(8 "In3.Cu" signal "GND1")
		(10 "In4.Cu" signal "IN2")
		(12 "In5.Cu" signal "GND2")
		(14 "In6.Cu" signal "IN3")
		(16 "In7.Cu" signal "GND3")
		(18 "In8.Cu" signal "VCC")
		(20 "In9.Cu" signal "VCC1")
		(22 "In10.Cu" signal "GND4")
		(24 "In11.Cu" signal "IN4")
		(26 "In12.Cu" signal "GND5")
		(28 "In13.Cu" signal "IN5")
		(30 "In14.Cu" signal "GND6")
		(32 "In15.Cu" signal "IN6")
		(34 "In16.Cu" signal "GND7")
		(2 "B.Cu" signal "BOTTOM")
		(9 "F.Adhes" user "F.Adhesive")
		(11 "B.Adhes" user "B.Adhesive")
		(13 "F.Paste" user "Package Geometry/Pastemask Top")
		(15 "B.Paste" user "Package Geometry/Pastemask Bottom")
		(5 "F.SilkS" user "Ref Des/Silkscreen Top")
		(7 "B.SilkS" user "Ref Des/Silkscreen Bottom")
		(1 "F.Mask" user "Board Geometry/Soldermask Top")
		(3 "B.Mask" user "Board Geometry/Soldermask Bottom")
		(17 "Dwgs.User" user "User.Drawings")
		(19 "Cmts.User" user "User.Comments")
		(21 "Eco1.User" user "User.Eco1")
		(23 "Eco2.User" user "User.Eco2")
		(25 "Edge.Cuts" user "Board Geometry/Outline")
		(27 "Margin" user)
		(31 "F.CrtYd" user "Package Geometry/Place Bound Top")
		(29 "B.CrtYd" user "Package Geometry/Place Bound Bottom")
		(35 "F.Fab" user "Ref Des/Assembly Top")
		(33 "B.Fab" user "Ref Des/Assembly Bottom")
	)
	(footprint ""
		(layer "F.Cu")
		(at 75.546458 -20.950682 180)
		(property "Reference" "PR3821"
			(at 0 0 180)
			(layer "F.SilkS")
			(hide yes)
			(effects
				(font
					(size 1.27 1.27)
				)
			)
		)
		(property "Value" ""
			(at 0 0 180)
			(layer "F.Fab")
			(effects
				(font
					(size 1.27 1.27)
				)
			)
		)
		(duplicate_pad_numbers_are_jumpers no)
		(fp_line
			(start 0.7874 0.4064)
			(end -0.7874 0.4064)
			(stroke
				(width 0.1524)
				(type default)
			)
			(layer "F.SilkS")
		)
		(fp_line
			(start 0.7874 -0.4064)
			(end 0.7874 0.4064)
			(stroke
				(width 0.1524)
				(type default)
			)
			(layer "F.SilkS")
		)
		(fp_line
			(start -0.7874 0.4064)
			(end -0.7874 -0.4064)
			(stroke
				(width 0.1524)
				(type default)
			)
			(layer "F.SilkS")
		)
		(fp_line
			(start -0.7874 -0.4064)
			(end 0.7874 -0.4064)
			(stroke
				(width 0.1524)
				(type default)
			)
			(layer "F.SilkS")
		)
		(fp_line
			(start 0.67945 0.3048)
			(end 0.120396 0.3048)
			(stroke
				(width 0.1)
				(type default)
			)
			(layer "F.Fab")
		)
		(fp_line
			(start 0.67945 -0.3048)
			(end 0.67945 0.3048)
			(stroke
				(width 0.1)
				(type default)
			)
			(layer "F.Fab")
		)
		(fp_line
			(start 0.12065 -0.2794)
			(end 0.12065 -0.3048)
			(stroke
				(width 0.1)
				(type default)
			)
			(layer "F.Fab")
		)
		(fp_line
			(start 0.12065 -0.3048)
			(end 0.67945 -0.3048)
			(stroke
				(width 0.1)
				(type default)
			)
			(layer "F.Fab")
		)
		(fp_line
			(start 0.120396 0.3048)
			(end 0.120396 0.2794)
			(stroke
				(width 0.1)
				(type default)
			)
			(layer "F.Fab")
		)
		(fp_line
			(start 0.120396 0.2794)
			(end -0.12065 0.2794)
			(stroke
				(width 0.1)
				(type default)
			)
			(layer "F.Fab")
		)
		(fp_line
			(start -0.12065 0.3048)
			(end -0.67945 0.3048)
			(stroke
				(width 0.1)
				(type default)
			)
			(layer "F.Fab")
		)
		(fp_line
			(start -0.12065 0.2794)
			(end -0.12065 0.3048)
			(stroke
				(width 0.1)
				(type default)
			)
			(layer "F.Fab")
		)
		(fp_line
			(start -0.12065 -0.2794)
			(end 0.12065 -0.2794)
			(stroke
				(width 0.1)
				(type default)
			)
			(layer "F.Fab")
		)
		(fp_line
			(start -0.12065 -0.305054)
			(end -0.12065 -0.2794)
			(stroke
				(width 0.1)
				(type default)
			)
			(layer "F.Fab")
		)
		(fp_line
			(start -0.67945 0.3048)
			(end -0.67945 -0.305054)
			(stroke
				(width 0.1)
				(type default)
			)
			(layer "F.Fab")
		)
		(fp_line
			(start -0.67945 -0.305054)
			(end -0.12065 -0.305054)
			(stroke
				(width 0.1)
				(type default)
			)
			(layer "F.Fab")
		)
		(pad "1" smd circle
			(at -0.40005 0 180)
			(size 0 0)
			(layers "F.Cu" "F.Mask" "F.Paste")
			(net "P12V_OCP_CB_2")
		)
		(pad "2" smd circle
			(at 0.40005 0 180)
			(size 0 0)
			(layers "F.Cu" "F.Mask" "F.Paste")
			(net "GND")
		)
	)
	(footprint ""
		(layer "F.Cu")
		(at 166.42588 -436.971948)
		(property "Reference" "U253"
			(at -1.43256 -2.86385 0)
			(unlocked yes)
			(layer "F.SilkS")
			(effects
				(font
					(size 0.7874 0.5842)
					(thickness 0.1524)
				)
				(justify left)
			)
		)
		(property "Value" ""
			(at 0 0 0)
			(layer "F.Fab")
			(effects
				(font
					(size 1.27 1.27)
				)
			)
		)
		(duplicate_pad_numbers_are_jumpers no)
		(fp_line
			(start -1.3462 -1.100074)
			(end -0.670052 -1.100074)
			(stroke
				(width 0.1524)
				(type default)
			)
			(layer "F.SilkS")
		)
		(fp_line
			(start -1.3462 1.100074)
			(end -1.3462 -1.100074)
			(stroke
				(width 0.1524)
				(type default)
			)
			(layer "F.SilkS")
		)
		(fp_line
			(start -0.670052 -1.100074)
			(end 0 -0.381)
			(stroke
				(width 0.1524)
				(type default)
			)
			(layer "F.SilkS")
		)
		(fp_line
			(start 0 -0.381)
			(end 0.670052 -1.100074)
			(stroke
				(width 0.1524)
				(type default)
			)
			(layer "F.SilkS")
		)
		(fp_line
			(start 0.670052 -1.100074)
			(end 1.3462 -1.100074)
			(stroke
				(width 0.1524)
				(type default)
			)
			(layer "F.SilkS")
		)
		(fp_line
			(start 1.3462 -1.100074)
			(end 1.3462 1.100074)
			(stroke
				(width 0.1524)
				(type default)
			)
			(layer "F.SilkS")
		)
		(fp_line
			(start 1.3462 1.100074)
			(end -1.3462 1.100074)
			(stroke
				(width 0.1524)
				(type default)
			)
			(layer "F.SilkS")
		)
		(fp_poly
			(pts
				(xy -1.056894 -1.39446) (xy -1.437894 -2.15646) (xy -0.675894 -2.15646)
			)
			(stroke
				(width 0)
				(type default)
			)
			(fill yes)
			(layer "F.SilkS")
		)
		(fp_line
			(start -1.100074 -0.8001)
			(end -0.670052 -0.8001)
			(stroke
				(width 0.1)
				(type default)
			)
			(layer "F.Fab")
		)
		(fp_line
			(start -1.100074 0.8001)
			(end -1.100074 -0.8001)
			(stroke
				(width 0.1)
				(type default)
			)
			(layer "F.Fab")
		)
		(fp_line
			(start -0.670052 -1.100074)
			(end 0.670052 -1.100074)
			(stroke
				(width 0.1)
				(type default)
			)
			(layer "F.Fab")
		)
		(fp_line
			(start -0.670052 -0.8001)
			(end -0.670052 -1.100074)
			(stroke
				(width 0.1)
				(type default)
			)
			(layer "F.Fab")
		)
		(fp_line
			(start -0.670052 0.8001)
			(end -1.100074 0.8001)
			(stroke
				(width 0.1)
				(type default)
			)
			(layer "F.Fab")
		)
		(fp_line
			(start -0.670052 0.8001)
			(end -0.670052 -0.8001)
			(stroke
				(width 0.1)
				(type default)
			)
			(layer "F.Fab")
		)
		(fp_line
			(start -0.670052 1.100074)
			(end -0.670052 0.8001)
			(stroke
				(width 0.1)
				(type default)
			)
			(layer "F.Fab")
		)
		(fp_line
			(start 0.670052 -1.100074)
			(end 0.670052 -0.8001)
			(stroke
				(width 0.1)
				(type default)
			)
			(layer "F.Fab")
		)
		(fp_line
			(start 0.670052 -0.8001)
			(end 0.670052 0.8001)
			(stroke
				(width 0.1)
				(type default)
			)
			(layer "F.Fab")
		)
		(fp_line
			(start 0.670052 -0.8001)
			(end 1.100074 -0.8001)
			(stroke
				(width 0.1)
				(type default)
			)
			(layer "F.Fab")
		)
		(fp_line
			(start 0.670052 0.8001)
			(end 0.670052 1.100074)
			(stroke
				(width 0.1)
				(type default)
			)
			(layer "F.Fab")
		)
		(fp_line
			(start 0.670052 1.100074)
			(end -0.670052 1.100074)
			(stroke
				(width 0.1)
				(type default)
			)
			(layer "F.Fab")
		)
		(fp_line
			(start 1.100074 -0.8001)
			(end 1.100074 0.8001)
			(stroke
				(width 0.1)
				(type default)
			)
			(layer "F.Fab")
		)
		(fp_line
			(start 1.100074 0.8001)
			(end 0.670052 0.8001)
			(stroke
				(width 0.1)
				(type default)
			)
			(layer "F.Fab")
		)
		(fp_poly
			(pts
				(xy -1.524 -0.649986) (xy -2.286 -1.030986) (xy -2.286 -0.268986)
			)
			(stroke
				(width 0)
				(type default)
			)
			(fill yes)
			(layer "F.Fab")
		)
		(pad "1" smd rect
			(at -0.94996 -0.649986 270)
			(size 0.4064 0.508)
			(layers "F.Cu" "F.Mask" "F.Paste")
			(net "GPU_FPGA_BOOT_EN")
		)
		(pad "2" smd rect
			(at -0.94996 0 270)
			(size 0.4064 0.508)
			(layers "F.Cu" "F.Mask" "F.Paste")
			(net "GND")
		)
		(pad "3" smd rect
			(at -0.94996 0.649986 270)
			(size 0.4064 0.508)
			(layers "F.Cu" "F.Mask" "F.Paste")
			(net "GPU_BASE_STBY_EN")
		)
		(pad "4" smd rect
			(at 0.94996 0.649986 270)
			(size 0.4064 0.508)
			(layers "F.Cu" "F.Mask" "F.Paste")
			(net "GPU_BASE_STBY_EN_BUF_R")
		)
		(pad "5" smd rect
			(at 0.94996 0 270)
			(size 0.4064 0.508)
			(layers "F.Cu" "F.Mask" "F.Paste")
			(net "P3V3_AUX")
		)
		(pad "6" smd rect
			(at 0.94996 -0.649986 270)
			(size 0.4064 0.508)
			(layers "F.Cu" "F.Mask" "F.Paste")
			(net "GPU_FPGA_BOOT_EN_BUF_R")
		)
	)
)
